# BASEBOARD_FAB2 (Tioga Pass) — schematic netlist excerpt (pin names and nets, part order shuffled) for the footprints in the layout excerpt that follows; sources: Cadence DE-HDL packaged netlist, KiCad conversion of Wiwynn_Tioga_Pass_MB.brd

Q1E1  2SB2907A-B0-00001-GP  pkg DISCRET-GB1  page 167
  B  = ISENSE_TMP421_2_BC
  C  = ISENSE_TMP421_2_BC
  E  = ISENSE_TMP421_2_E

R4D31  RES  2.26K 1.0% EMPTY  pkg 0402  page 201 : A = P3V3_STBY ; B = PU_VR_PVCCIN_CPU0_IMON

(kicad_pcb
	(version 20260206)
	(generator "pcbnew")
	(generator_version "10.0")
	(general
		(thickness 1.6)
		(legacy_teardrops no)
	)
	(paper "A4")
	(title_block
		(title "Wiwynn_Tioga_Pass_MB.brd")
		(comment 1 "Tioga Pass / footprints 374-375 of 4770")
	)
	(layers
		(0 "F.Cu" signal "TOP")
		(4 "In1.Cu" signal "L2GND")
		(6 "In2.Cu" signal "L3")
		(8 "In3.Cu" signal "L4GND")
		(10 "In4.Cu" signal "L5")
		(12 "In5.Cu" signal "L6GND")
		(14 "In6.Cu" signal "L7VCC")
		(16 "In7.Cu" signal "L8VCC")
		(18 "In8.Cu" signal "L9GND")
		(20 "In9.Cu" signal "L10")
		(22 "In10.Cu" signal "L11GND")
		(24 "In11.Cu" signal "L12")
		(26 "In12.Cu" signal "L13GND")
		(2 "B.Cu" signal "BOTTOM")
		(9 "F.Adhes" user "F.Adhesive")
		(11 "B.Adhes" user "B.Adhesive")
		(13 "F.Paste" user "Package Geometry/Pastemask Top")
		(15 "B.Paste" user "Package Geometry/Pastemask Bottom")
		(5 "F.SilkS" user "Ref Des/Silkscreen Top")
		(7 "B.SilkS" user "Ref Des/Silkscreen Bottom")
		(1 "F.Mask" user "Board Geometry/Soldermask Top")
		(3 "B.Mask" user "Board Geometry/Soldermask Bottom")
		(17 "Dwgs.User" user "User.Drawings")
		(19 "Cmts.User" user "User.Comments")
		(21 "Eco1.User" user "User.Eco1")
		(23 "Eco2.User" user "User.Eco2")
		(25 "Edge.Cuts" user "Board Geometry/Outline")
		(27 "Margin" user)
		(31 "F.CrtYd" user "Package Geometry/Place Bound Top")
		(29 "B.CrtYd" user "Package Geometry/Place Bound Bottom")
		(35 "F.Fab" user "Ref Des/Assembly Top")
		(33 "B.Fab" user "Ref Des/Assembly Bottom")
	)
	(footprint ""
		(layer "F.Cu")
		(at 18.525744 -51.3842 180)
		(property "Reference" "Q1E1"
			(at 0 0 180)
			(layer "F.SilkS")
			(hide yes)
			(effects
				(font
					(size 1.27 1.27)
				)
			)
		)
		(property "Value" "*"
			(at -4.8514 -0.40005 180)
			(unlocked yes)
			(layer "F.Fab")
			(hide yes)
			(effects
				(font
					(size 0.889 0.889)
					(thickness 0.1524)
				)
			)
		)
		(property "Device Type" "2SB2907A-B0-00001-GP_DISCRET-GA"
			(at -4.8514 -1.92405 180)
			(unlocked yes)
			(layer "F.Fab")
			(hide yes)
			(effects
				(font
					(size 0.889 0.889)
					(thickness 0.1524)
				)
			)
		)
		(duplicate_pad_numbers_are_jumpers no)
		(fp_line
			(start 3.3274 0.8255)
			(end 2.59334 0.8255)
			(stroke
				(width 0.1524)
				(type default)
			)
			(layer "F.SilkS")
		)
		(fp_line
			(start 3.3274 -0.8255)
			(end 3.3274 0.8255)
			(stroke
				(width 0.1524)
				(type default)
			)
			(layer "F.SilkS")
		)
		(fp_line
			(start 2.460752 -0.8255)
			(end 3.3274 -0.8255)
			(stroke
				(width 0.1524)
				(type default)
			)
			(layer "F.SilkS")
		)
		(fp_line
			(start -2.188718 -1.3208)
			(end 2.188718 -1.3208)
			(stroke
				(width 0.1524)
				(type default)
			)
			(layer "F.SilkS")
		)
		(fp_line
			(start -2.59334 0.8255)
			(end -3.3274 0.8255)
			(stroke
				(width 0.1524)
				(type default)
			)
			(layer "F.SilkS")
		)
		(fp_line
			(start -3.3274 0.8255)
			(end -3.3274 -0.8255)
			(stroke
				(width 0.1524)
				(type default)
			)
			(layer "F.SilkS")
		)
		(fp_line
			(start -3.3274 -0.8255)
			(end -2.460752 -0.8255)
			(stroke
				(width 0.1524)
				(type default)
			)
			(layer "F.SilkS")
		)
		(fp_arc
			(start 2.59334 0.8255)
			(mid 0 2.870159)
			(end -2.59334 0.8255)
			(stroke
				(width 0.1524)
				(type default)
			)
			(layer "F.SilkS")
		)
		(fp_arc
			(start 2.188718 -1.3208)
			(mid 2.337892 -1.080376)
			(end 2.460752 -0.8255)
			(stroke
				(width 0.1524)
				(type default)
			)
			(layer "F.SilkS")
		)
		(fp_arc
			(start -2.460752 -0.8255)
			(mid -2.337885 -1.080372)
			(end -2.188718 -1.3208)
			(stroke
				(width 0.1524)
				(type default)
			)
			(layer "F.SilkS")
		)
		(fp_poly
			(pts
				(arc
					(start 2.413 0.2286)
					(mid 0 2.616334)
					(end -2.413 0.2286)
				)
				(xy -2.7432 0.2286) (xy -2.7432 -0.2286)
				(arc
					(start -2.374138 -0.2286)
					(mid -2.252325 -0.662833)
					(end -2.051812 -1.0668)
				)
				(arc
					(start 2.051812 -1.0668)
					(mid 2.252296 -0.662822)
					(end 2.374138 -0.2286)
				)
				(xy 2.7432 -0.2286) (xy 2.7432 0.2286)
			)
			(stroke
				(width 0)
				(type default)
			)
			(fill no)
			(layer "F.CrtYd")
		)
		(fp_poly
			(pts
				(arc
					(start 2.786634 1.0795)
					(mid 0 3.124369)
					(end -2.786634 1.0795)
				)
				(xy -3.5814 1.0795) (xy -3.5814 -1.0795)
				(arc
					(start -2.624328 -1.0795)
					(mid -2.483414 -1.33481)
					(end -2.31775 -1.5748)
				)
				(xy -0.000762 -1.5748) (xy -0.000762 -1.067054)
				(arc
					(start -2.052066 -1.067054)
					(mid -2.252571 -0.663082)
					(end -2.374392 -0.228854)
				)
				(xy -2.743454 -0.228854) (xy -2.743454 0.228854)
				(arc
					(start -2.413254 0.228854)
					(mid 0 2.61659)
					(end 2.413254 0.228854)
				)
				(xy 2.743454 0.228854) (xy 2.743454 -0.228854)
				(arc
					(start 2.374392 -0.228854)
					(mid 2.252549 -0.663073)
					(end 2.052066 -1.067054)
				)
				(xy 0.000762 -1.067054) (xy 0.000762 -1.5748)
				(arc
					(start 2.31775 -1.5748)
					(mid 2.483417 -1.334811)
					(end 2.624328 -1.0795)
				)
				(xy 3.5814 -1.0795) (xy 3.5814 1.0795)
			)
			(stroke
				(width 0)
				(type default)
			)
			(fill no)
			(layer "F.CrtYd")
		)
		(fp_poly
			(pts
				(arc
					(start 2.786634 1.0795)
					(mid 0 3.124369)
					(end -2.786634 1.0795)
				)
				(xy -3.5814 1.0795) (xy -3.5814 -1.0795)
				(arc
					(start -2.624328 -1.0795)
					(mid -2.483414 -1.33481)
					(end -2.31775 -1.5748)
				)
				(arc
					(start 2.31775 -1.5748)
					(mid 2.483417 -1.334811)
					(end 2.624328 -1.0795)
				)
				(xy 3.5814 -1.0795) (xy 3.5814 1.0795)
			)
			(stroke
				(width 0)
				(type default)
			)
			(fill no)
			(layer "F.Fab")
		)
		(pad "B" thru_hole circle
			(at 0 0 180)
			(size 1.143 1.143)
			(drill 0.7874)
			(layers "*.Cu" "*.Mask")
			(remove_unused_layers no)
			(net "ISENSE_TMP421_2_BC")
			(clearance 0.1778)
			(thermal_gap 0.1778)
		)
		(pad "C" thru_hole circle
			(at -2.500122 0 180)
			(size 1.143 1.143)
			(drill 0.7874)
			(layers "*.Cu" "*.Mask")
			(remove_unused_layers no)
			(net "ISENSE_TMP421_2_BC")
			(clearance 0.1778)
			(thermal_gap 0.1778)
		)
		(pad "E" thru_hole circle
			(at 2.500122 0 180)
			(size 1.143 1.143)
			(drill 0.7874)
			(layers "*.Cu" "*.Mask")
			(remove_unused_layers no)
			(net "ISENSE_TMP421_2_E")
			(clearance 0.1778)
			(thermal_gap 0.1778)
		)
	)
	(footprint ""
		(layer "F.Cu")
		(at 186.4868 -76.4921)
		(property "Reference" "R4D31"
			(at 0 0 0)
			(layer "F.SilkS")
			(hide yes)
			(effects
				(font
					(size 1.27 1.27)
				)
			)
		)
		(property "Value" ""
			(at 0 0 0)
			(layer "F.Fab")
			(effects
				(font
					(size 1.27 1.27)
				)
			)
		)
		(duplicate_pad_numbers_are_jumpers no)
		(fp_rect
			(start -0.2794 0.9906)
			(end 0.2794 -0.1016)
			(stroke
				(width 0)
				(type default)
			)
			(fill no)
			(layer "F.CrtYd")
		)
		(fp_line
			(start -0.2794 -0.1016)
			(end -0.2794 0.9906)
			(stroke
				(width 0.1)
				(type default)
			)
			(layer "F.Fab")
		)
		(fp_line
			(start -0.2794 0.9906)
			(end 0.2794 0.9906)
			(stroke
				(width 0.1)
				(type default)
			)
			(layer "F.Fab")
		)
		(fp_line
			(start 0.2794 -0.1016)
			(end -0.2794 -0.1016)
			(stroke
				(width 0.1)
				(type default)
			)
			(layer "F.Fab")
		)
		(fp_line
			(start 0.2794 0.9906)
			(end 0.2794 -0.1016)
			(stroke
				(width 0.1)
				(type default)
			)
			(layer "F.Fab")
		)
		(pad "1" smd rect
			(at 0 0)
			(size 0.508 0.508)
			(layers "F.Cu" "F.Mask" "F.Paste")
			(net "P3V3_STBY")
		)
		(pad "2" smd rect
			(at 0 0.889)
			(size 0.508 0.508)
			(layers "F.Cu" "F.Mask" "F.Paste")
			(net "PU_VR_PVCCIN_CPU0_IMON")
		)
		(zone
			(layer "F.Cu")
			(hatch none 0.5)
			(connect_pads
				(clearance 0)
			)
			(min_thickness 0.25)
			(keepout
				(tracks not_allowed)
				(vias allowed)
				(pads allowed)
				(copperpour not_allowed)
				(footprints allowed)
			)
			(placement
				(enabled no)
				(sheetname "")
			)
			(fill
				(thermal_gap 0.5)
				(thermal_bridge_width 0.5)
				(island_removal_mode 0)
			)
			(polygon
				(pts
					(xy 186.2328 -75.8571) (xy 186.7408 -75.8571) (xy 186.7408 -76.2381) (xy 186.2328 -76.2381)
				)
			)
		)
		(zone
			(layer "F.Cu")
			(hatch none 0.5)
			(connect_pads
				(clearance 0)
			)
			(min_thickness 0.25)
			(keepout
				(tracks allowed)
				(vias not_allowed)
				(pads allowed)
				(copperpour not_allowed)
				(footprints allowed)
			)
			(placement
				(enabled no)
				(sheetname "")
			)
			(fill
				(thermal_gap 0.5)
				(thermal_bridge_width 0.5)
				(island_removal_mode 0)
			)
			(polygon
				(pts
					(xy 186.2328 -75.8571) (xy 186.7408 -75.8571) (xy 186.7408 -76.2381) (xy 186.2328 -76.2381)
				)
			)
		)
	)
)
